# T6G (Grand Teton) — schematic netlist excerpt (pin names and nets, part order shuffled) for the footprints in the layout excerpt that follows; sources: Cadence DE-HDL packaged netlist, KiCad conversion of 04192023_DAF0TMB3IC0_F0TG_MB_C_brd_V02_OCP.brd

R1131  Q_RES  1K 1% CHIP  pkg 0402LF  page 136 : A = P3V3_AUX ; B = P12V_OCP_SFF_EN_R3
C1065  Q_CAP  0.1UF 25V 10% X7R  pkg 0402  page 142 : A = P3V3_AUX ; B = GND

(kicad_pcb
	(version 20260206)
	(generator "pcbnew")
	(generator_version "10.0")
	(general
		(thickness 1.6)
		(legacy_teardrops no)
	)
	(paper "A4")
	(title_block
		(title "04192023_DAF0TMB3IC0_F0TG_MB_C_brd_V02_OCP.brd")
		(comment 1 "Grand Teton / footprints 4258-4259 of 8354")
	)
	(layers
		(0 "F.Cu" signal "TOP")
		(4 "In1.Cu" signal "GND")
		(6 "In2.Cu" signal "IN1")
		(8 "In3.Cu" signal "GND1")
		(10 "In4.Cu" signal "IN2")
		(12 "In5.Cu" signal "GND2")
		(14 "In6.Cu" signal "IN3")
		(16 "In7.Cu" signal "GND3")
		(18 "In8.Cu" signal "VCC")
		(20 "In9.Cu" signal "VCC1")
		(22 "In10.Cu" signal "GND4")
		(24 "In11.Cu" signal "IN4")
		(26 "In12.Cu" signal "GND5")
		(28 "In13.Cu" signal "IN5")
		(30 "In14.Cu" signal "GND6")
		(32 "In15.Cu" signal "IN6")
		(34 "In16.Cu" signal "GND7")
		(2 "B.Cu" signal "BOTTOM")
		(9 "F.Adhes" user "F.Adhesive")
		(11 "B.Adhes" user "B.Adhesive")
		(13 "F.Paste" user "Package Geometry/Pastemask Top")
		(15 "B.Paste" user "Package Geometry/Pastemask Bottom")
		(5 "F.SilkS" user "Ref Des/Silkscreen Top")
		(7 "B.SilkS" user "Ref Des/Silkscreen Bottom")
		(1 "F.Mask" user "Board Geometry/Soldermask Top")
		(3 "B.Mask" user "Board Geometry/Soldermask Bottom")
		(17 "Dwgs.User" user "User.Drawings")
		(19 "Cmts.User" user "User.Comments")
		(21 "Eco1.User" user "User.Eco1")
		(23 "Eco2.User" user "User.Eco2")
		(25 "Edge.Cuts" user "Board Geometry/Outline")
		(27 "Margin" user)
		(31 "F.CrtYd" user "Package Geometry/Place Bound Top")
		(29 "B.CrtYd" user "Package Geometry/Place Bound Bottom")
		(35 "F.Fab" user "Ref Des/Assembly Top")
		(33 "B.Fab" user "Ref Des/Assembly Bottom")
	)
	(footprint ""
		(layer "F.Cu")
		(at 156.718 -106.172 180)
		(property "Reference" "R1131"
			(at 0 0 180)
			(layer "F.SilkS")
			(hide yes)
			(effects
				(font
					(size 1.27 1.27)
				)
			)
		)
		(property "Value" ""
			(at 0 0 180)
			(layer "F.Fab")
			(effects
				(font
					(size 1.27 1.27)
				)
			)
		)
		(duplicate_pad_numbers_are_jumpers no)
		(fp_line
			(start 0.7874 0.4064)
			(end -0.7874 0.4064)
			(stroke
				(width 0.1524)
				(type default)
			)
			(layer "F.SilkS")
		)
		(fp_line
			(start 0.7874 -0.4064)
			(end 0.7874 0.4064)
			(stroke
				(width 0.1524)
				(type default)
			)
			(layer "F.SilkS")
		)
		(fp_line
			(start -0.7874 0.4064)
			(end -0.7874 -0.4064)
			(stroke
				(width 0.1524)
				(type default)
			)
			(layer "F.SilkS")
		)
		(fp_line
			(start -0.7874 -0.4064)
			(end 0.7874 -0.4064)
			(stroke
				(width 0.1524)
				(type default)
			)
			(layer "F.SilkS")
		)
		(fp_line
			(start 0.67945 0.3048)
			(end 0.120396 0.3048)
			(stroke
				(width 0.1)
				(type default)
			)
			(layer "F.Fab")
		)
		(fp_line
			(start 0.67945 -0.3048)
			(end 0.67945 0.3048)
			(stroke
				(width 0.1)
				(type default)
			)
			(layer "F.Fab")
		)
		(fp_line
			(start 0.12065 -0.2794)
			(end 0.12065 -0.3048)
			(stroke
				(width 0.1)
				(type default)
			)
			(layer "F.Fab")
		)
		(fp_line
			(start 0.12065 -0.3048)
			(end 0.67945 -0.3048)
			(stroke
				(width 0.1)
				(type default)
			)
			(layer "F.Fab")
		)
		(fp_line
			(start 0.120396 0.3048)
			(end 0.120396 0.2794)
			(stroke
				(width 0.1)
				(type default)
			)
			(layer "F.Fab")
		)
		(fp_line
			(start 0.120396 0.2794)
			(end -0.12065 0.2794)
			(stroke
				(width 0.1)
				(type default)
			)
			(layer "F.Fab")
		)
		(fp_line
			(start -0.12065 0.3048)
			(end -0.67945 0.3048)
			(stroke
				(width 0.1)
				(type default)
			)
			(layer "F.Fab")
		)
		(fp_line
			(start -0.12065 0.2794)
			(end -0.12065 0.3048)
			(stroke
				(width 0.1)
				(type default)
			)
			(layer "F.Fab")
		)
		(fp_line
			(start -0.12065 -0.2794)
			(end 0.12065 -0.2794)
			(stroke
				(width 0.1)
				(type default)
			)
			(layer "F.Fab")
		)
		(fp_line
			(start -0.12065 -0.305054)
			(end -0.12065 -0.2794)
			(stroke
				(width 0.1)
				(type default)
			)
			(layer "F.Fab")
		)
		(fp_line
			(start -0.67945 0.3048)
			(end -0.67945 -0.305054)
			(stroke
				(width 0.1)
				(type default)
			)
			(layer "F.Fab")
		)
		(fp_line
			(start -0.67945 -0.305054)
			(end -0.12065 -0.305054)
			(stroke
				(width 0.1)
				(type default)
			)
			(layer "F.Fab")
		)
		(pad "1" smd circle
			(at -0.40005 0 180)
			(size 0 0)
			(layers "F.Cu" "F.Mask" "F.Paste")
			(net "P3V3_AUX")
		)
		(pad "2" smd circle
			(at 0.40005 0 180)
			(size 0 0)
			(layers "F.Cu" "F.Mask" "F.Paste")
			(net "P12V_OCP_SFF_EN_R3")
		)
	)
	(footprint ""
		(layer "F.Cu")
		(at 55.753 -39.751)
		(property "Reference" "C1065"
			(at 0 0 0)
			(layer "F.SilkS")
			(hide yes)
			(effects
				(font
					(size 1.27 1.27)
				)
			)
		)
		(property "Value" ""
			(at 0 0 0)
			(layer "F.Fab")
			(effects
				(font
					(size 1.27 1.27)
				)
			)
		)
		(duplicate_pad_numbers_are_jumpers no)
		(fp_line
			(start -0.7874 -0.4064)
			(end 0.7874 -0.4064)
			(stroke
				(width 0.1524)
				(type default)
			)
			(layer "F.SilkS")
		)
		(fp_line
			(start -0.7874 0.4064)
			(end -0.7874 -0.4064)
			(stroke
				(width 0.1524)
				(type default)
			)
			(layer "F.SilkS")
		)
		(fp_line
			(start 0.7874 -0.4064)
			(end 0.7874 0.4064)
			(stroke
				(width 0.1524)
				(type default)
			)
			(layer "F.SilkS")
		)
		(fp_line
			(start 0.7874 0.4064)
			(end -0.7874 0.4064)
			(stroke
				(width 0.1524)
				(type default)
			)
			(layer "F.SilkS")
		)
		(fp_line
			(start -0.67945 -0.305054)
			(end -0.12065 -0.305054)
			(stroke
				(width 0.1)
				(type default)
			)
			(layer "F.Fab")
		)
		(fp_line
			(start -0.67945 0.3048)
			(end -0.67945 -0.305054)
			(stroke
				(width 0.1)
				(type default)
			)
			(layer "F.Fab")
		)
		(fp_line
			(start -0.12065 -0.305054)
			(end -0.12065 -0.2794)
			(stroke
				(width 0.1)
				(type default)
			)
			(layer "F.Fab")
		)
		(fp_line
			(start -0.12065 -0.2794)
			(end 0.12065 -0.2794)
			(stroke
				(width 0.1)
				(type default)
			)
			(layer "F.Fab")
		)
		(fp_line
			(start -0.12065 0.2794)
			(end -0.12065 0.3048)
			(stroke
				(width 0.1)
				(type default)
			)
			(layer "F.Fab")
		)
		(fp_line
			(start -0.12065 0.3048)
			(end -0.67945 0.3048)
			(stroke
				(width 0.1)
				(type default)
			)
			(layer "F.Fab")
		)
		(fp_line
			(start 0.120396 0.2794)
			(end -0.12065 0.2794)
			(stroke
				(width 0.1)
				(type default)
			)
			(layer "F.Fab")
		)
		(fp_line
			(start 0.120396 0.3048)
			(end 0.120396 0.2794)
			(stroke
				(width 0.1)
				(type default)
			)
			(layer "F.Fab")
		)
		(fp_line
			(start 0.12065 -0.3048)
			(end 0.67945 -0.3048)
			(stroke
				(width 0.1)
				(type default)
			)
			(layer "F.Fab")
		)
		(fp_line
			(start 0.12065 -0.2794)
			(end 0.12065 -0.3048)
			(stroke
				(width 0.1)
				(type default)
			)
			(layer "F.Fab")
		)
		(fp_line
			(start 0.67945 -0.3048)
			(end 0.67945 0.3048)
			(stroke
				(width 0.1)
				(type default)
			)
			(layer "F.Fab")
		)
		(fp_line
			(start 0.67945 0.3048)
			(end 0.120396 0.3048)
			(stroke
				(width 0.1)
				(type default)
			)
			(layer "F.Fab")
		)
		(pad "1" smd circle
			(at -0.40005 0)
			(size 0 0)
			(layers "F.Cu" "F.Mask" "F.Paste")
			(net "P3V3_AUX")
		)
		(pad "2" smd circle
			(at 0.40005 0)
			(size 0 0)
			(layers "F.Cu" "F.Mask" "F.Paste")
			(net "GND")
		)
	)
)
